(kicad_pcb
	(version 20260206)
	(generator "pcbnew")
	(generator_version "10.0")
	(general
		(thickness 1.6)
		(legacy_teardrops no)
	)
	(paper "A4")
	(title_block
		(title "01162023_DA0F0TEBIF0_F0T_Expander_BD_F_brd_V02_OCP.brd")
		(comment 1 "Grand Teton / footprints 1284-1289 of 9728")
	)
	(layers
		(0 "F.Cu" signal "TOP")
		(4 "In1.Cu" signal "GND")
		(6 "In2.Cu" signal "VCC")
		(8 "In3.Cu" signal "VCC1")
		(10 "In4.Cu" signal "GND1")
		(12 "In5.Cu" signal "IN1")
		(14 "In6.Cu" signal "GND2")
		(16 "In7.Cu" signal "IN2")
		(18 "In8.Cu" signal "GND3")
		(20 "In9.Cu" signal "IN3")
		(22 "In10.Cu" signal "GND4")
		(24 "In11.Cu" signal "IN4")
		(26 "In12.Cu" signal "GND5")
		(28 "In13.Cu" signal "IN5")
		(30 "In14.Cu" signal "GND6")
		(32 "In15.Cu" signal "IN6")
		(34 "In16.Cu" signal "GND7")
		(2 "B.Cu" signal "BOTTOM")
		(9 "F.Adhes" user "F.Adhesive")
		(11 "B.Adhes" user "B.Adhesive")
		(13 "F.Paste" user "Package Geometry/Pastemask Top")
		(15 "B.Paste" user "Package Geometry/Pastemask Bottom")
		(5 "F.SilkS" user "Ref Des/Silkscreen Top")
		(7 "B.SilkS" user "Ref Des/Silkscreen Bottom")
		(1 "F.Mask" user "Board Geometry/Soldermask Top")
		(3 "B.Mask" user "Board Geometry/Soldermask Bottom")
		(17 "Dwgs.User" user "User.Drawings")
		(19 "Cmts.User" user "User.Comments")
		(21 "Eco1.User" user "User.Eco1")
		(23 "Eco2.User" user "User.Eco2")
		(25 "Edge.Cuts" user "Board Geometry/Outline")
		(27 "Margin" user)
		(31 "F.CrtYd" user "Package Geometry/Place Bound Top")
		(29 "B.CrtYd" user "Package Geometry/Place Bound Bottom")
		(35 "F.Fab" user "Ref Des/Assembly Top")
		(33 "B.Fab" user "Ref Des/Assembly Bottom")
	)
	(footprint ""
		(layer "F.Cu")
		(at 218.37396 -26.31186 -90)
		(property "Reference" "U405"
			(at -0.15494 -2.40411 90)
			(unlocked yes)
			(layer "F.SilkS")
			(effects
				(font
					(size 0.7874 0.5842)
					(thickness 0.1524)
				)
			)
		)
		(property "Value" ""
			(at 0 0 270)
			(layer "F.Fab")
			(effects
				(font
					(size 1.27 1.27)
				)
			)
		)
		(duplicate_pad_numbers_are_jumpers no)
		(fp_line
			(start -1.949958 1.610106)
			(end -1.949958 -1.610106)
			(stroke
				(width 0.1524)
				(type default)
			)
			(layer "F.SilkS")
		)
		(fp_line
			(start 1.949958 1.610106)
			(end -1.949958 1.610106)
			(stroke
				(width 0.1524)
				(type default)
			)
			(layer "F.SilkS")
		)
		(fp_line
			(start 1.949958 -1.560068)
			(end 1.949958 1.610106)
			(stroke
				(width 0.1524)
				(type default)
			)
			(layer "F.SilkS")
		)
		(fp_line
			(start -1.949958 -1.610106)
			(end 1.949958 -1.610106)
			(stroke
				(width 0.1524)
				(type default)
			)
			(layer "F.SilkS")
		)
		(fp_line
			(start -0.750062 1.560068)
			(end -0.750062 -1.560068)
			(stroke
				(width 0.1)
				(type default)
			)
			(layer "F.Fab")
		)
		(fp_line
			(start 0.750062 1.560068)
			(end -0.750062 1.560068)
			(stroke
				(width 0.1)
				(type default)
			)
			(layer "F.Fab")
		)
		(fp_line
			(start -0.750062 -1.560068)
			(end 0.750062 -1.560068)
			(stroke
				(width 0.1)
				(type default)
			)
			(layer "F.Fab")
		)
		(fp_line
			(start 0.750062 -1.560068)
			(end 0.750062 1.560068)
			(stroke
				(width 0.1)
				(type default)
			)
			(layer "F.Fab")
		)
		(pad "D" smd rect
			(at 1.100074 0 180)
			(size 1.016 1.4224)
			(layers "F.Cu" "F.Mask" "F.Paste")
			(net "SSD7_LED_ISO_N")
		)
		(pad "G" smd rect
			(at -1.100074 -0.94996 180)
			(size 1.016 1.4224)
			(layers "F.Cu" "F.Mask" "F.Paste")
			(net "SSD7_LED_R")
		)
		(pad "S" smd rect
			(at -1.100074 0.94996 180)
			(size 1.016 1.4224)
			(layers "F.Cu" "F.Mask" "F.Paste")
			(net "GND")
		)
	)
	(footprint ""
		(layer "F.Cu")
		(at 166.330884 -192.820798)
		(property "Reference" "R3405"
			(at 0 0 0)
			(layer "F.SilkS")
			(hide yes)
			(effects
				(font
					(size 1.27 1.27)
				)
			)
		)
		(property "Value" ""
			(at 0 0 0)
			(layer "F.Fab")
			(effects
				(font
					(size 1.27 1.27)
				)
			)
		)
		(duplicate_pad_numbers_are_jumpers no)
		(fp_line
			(start -0.7874 -0.4064)
			(end 0.7874 -0.4064)
			(stroke
				(width 0.1524)
				(type default)
			)
			(layer "F.SilkS")
		)
		(fp_line
			(start -0.7874 0.4064)
			(end -0.7874 -0.4064)
			(stroke
				(width 0.1524)
				(type default)
			)
			(layer "F.SilkS")
		)
		(fp_line
			(start 0.7874 -0.4064)
			(end 0.7874 0.4064)
			(stroke
				(width 0.1524)
				(type default)
			)
			(layer "F.SilkS")
		)
		(fp_line
			(start 0.7874 0.4064)
			(end -0.7874 0.4064)
			(stroke
				(width 0.1524)
				(type default)
			)
			(layer "F.SilkS")
		)
		(fp_line
			(start -0.67945 -0.305054)
			(end -0.12065 -0.305054)
			(stroke
				(width 0.1)
				(type default)
			)
			(layer "F.Fab")
		)
		(fp_line
			(start -0.67945 0.3048)
			(end -0.67945 -0.305054)
			(stroke
				(width 0.1)
				(type default)
			)
			(layer "F.Fab")
		)
		(fp_line
			(start -0.12065 -0.305054)
			(end -0.12065 -0.2794)
			(stroke
				(width 0.1)
				(type default)
			)
			(layer "F.Fab")
		)
		(fp_line
			(start -0.12065 -0.2794)
			(end 0.12065 -0.2794)
			(stroke
				(width 0.1)
				(type default)
			)
			(layer "F.Fab")
		)
		(fp_line
			(start -0.12065 0.2794)
			(end -0.12065 0.3048)
			(stroke
				(width 0.1)
				(type default)
			)
			(layer "F.Fab")
		)
		(fp_line
			(start -0.12065 0.3048)
			(end -0.67945 0.3048)
			(stroke
				(width 0.1)
				(type default)
			)
			(layer "F.Fab")
		)
		(fp_line
			(start 0.120396 0.2794)
			(end -0.12065 0.2794)
			(stroke
				(width 0.1)
				(type default)
			)
			(layer "F.Fab")
		)
		(fp_line
			(start 0.120396 0.3048)
			(end 0.120396 0.2794)
			(stroke
				(width 0.1)
				(type default)
			)
			(layer "F.Fab")
		)
		(fp_line
			(start 0.12065 -0.3048)
			(end 0.67945 -0.3048)
			(stroke
				(width 0.1)
				(type default)
			)
			(layer "F.Fab")
		)
		(fp_line
			(start 0.12065 -0.2794)
			(end 0.12065 -0.3048)
			(stroke
				(width 0.1)
				(type default)
			)
			(layer "F.Fab")
		)
		(fp_line
			(start 0.67945 -0.3048)
			(end 0.67945 0.3048)
			(stroke
				(width 0.1)
				(type default)
			)
			(layer "F.Fab")
		)
		(fp_line
			(start 0.67945 0.3048)
			(end 0.120396 0.3048)
			(stroke
				(width 0.1)
				(type default)
			)
			(layer "F.Fab")
		)
		(pad "1" smd circle
			(at -0.40005 0)
			(size 0 0)
			(layers "F.Cu" "F.Mask" "F.Paste")
			(net "SPI_BIC1_MISO_LS01_R1")
		)
		(pad "2" smd circle
			(at 0.40005 0)
			(size 0 0)
			(layers "F.Cu" "F.Mask" "F.Paste")
			(net "SPI_BIC1_MISO_LS01_R")
		)
	)
	(footprint ""
		(layer "F.Cu")
		(at 168.343834 -42.84091)
		(property "Reference" "R560"
			(at 0 0 0)
			(layer "F.SilkS")
			(hide yes)
			(effects
				(font
					(size 1.27 1.27)
				)
			)
		)
		(property "Value" ""
			(at 0 0 0)
			(layer "F.Fab")
			(effects
				(font
					(size 1.27 1.27)
				)
			)
		)
		(duplicate_pad_numbers_are_jumpers no)
		(fp_line
			(start -0.7874 -0.4064)
			(end 0.7874 -0.4064)
			(stroke
				(width 0.1524)
				(type default)
			)
			(layer "F.SilkS")
		)
		(fp_line
			(start -0.7874 0.4064)
			(end -0.7874 -0.4064)
			(stroke
				(width 0.1524)
				(type default)
			)
			(layer "F.SilkS")
		)
		(fp_line
			(start 0.7874 -0.4064)
			(end 0.7874 0.4064)
			(stroke
				(width 0.1524)
				(type default)
			)
			(layer "F.SilkS")
		)
		(fp_line
			(start 0.7874 0.4064)
			(end -0.7874 0.4064)
			(stroke
				(width 0.1524)
				(type default)
			)
			(layer "F.SilkS")
		)
		(fp_line
			(start -0.67945 -0.305054)
			(end -0.12065 -0.305054)
			(stroke
				(width 0.1)
				(type default)
			)
			(layer "F.Fab")
		)
		(fp_line
			(start -0.67945 0.3048)
			(end -0.67945 -0.305054)
			(stroke
				(width 0.1)
				(type default)
			)
			(layer "F.Fab")
		)
		(fp_line
			(start -0.12065 -0.305054)
			(end -0.12065 -0.2794)
			(stroke
				(width 0.1)
				(type default)
			)
			(layer "F.Fab")
		)
		(fp_line
			(start -0.12065 -0.2794)
			(end 0.12065 -0.2794)
			(stroke
				(width 0.1)
				(type default)
			)
			(layer "F.Fab")
		)
		(fp_line
			(start -0.12065 0.2794)
			(end -0.12065 0.3048)
			(stroke
				(width 0.1)
				(type default)
			)
			(layer "F.Fab")
		)
		(fp_line
			(start -0.12065 0.3048)
			(end -0.67945 0.3048)
			(stroke
				(width 0.1)
				(type default)
			)
			(layer "F.Fab")
		)
		(fp_line
			(start 0.120396 0.2794)
			(end -0.12065 0.2794)
			(stroke
				(width 0.1)
				(type default)
			)
			(layer "F.Fab")
		)
		(fp_line
			(start 0.120396 0.3048)
			(end 0.120396 0.2794)
			(stroke
				(width 0.1)
				(type default)
			)
			(layer "F.Fab")
		)
		(fp_line
			(start 0.12065 -0.3048)
			(end 0.67945 -0.3048)
			(stroke
				(width 0.1)
				(type default)
			)
			(layer "F.Fab")
		)
		(fp_line
			(start 0.12065 -0.2794)
			(end 0.12065 -0.3048)
			(stroke
				(width 0.1)
				(type default)
			)
			(layer "F.Fab")
		)
		(fp_line
			(start 0.67945 -0.3048)
			(end 0.67945 0.3048)
			(stroke
				(width 0.1)
				(type default)
			)
			(layer "F.Fab")
		)
		(fp_line
			(start 0.67945 0.3048)
			(end 0.120396 0.3048)
			(stroke
				(width 0.1)
				(type default)
			)
			(layer "F.Fab")
		)
		(pad "1" smd circle
			(at -0.40005 0)
			(size 0 0)
			(layers "F.Cu" "F.Mask" "F.Paste")
			(net "SSD5_ADC_A1")
		)
		(pad "2" smd circle
			(at 0.40005 0)
			(size 0 0)
			(layers "F.Cu" "F.Mask" "F.Paste")
			(net "P3V3_AUX")
		)
	)
	(footprint ""
		(layer "F.Cu")
		(at 430.673764 -27.006296 -90)
		(property "Reference" "PC974"
			(at 0 0 270)
			(layer "F.SilkS")
			(hide yes)
			(effects
				(font
					(size 1.27 1.27)
				)
			)
		)
		(property "Value" ""
			(at 0 0 270)
			(layer "F.Fab")
			(effects
				(font
					(size 1.27 1.27)
				)
			)
		)
		(duplicate_pad_numbers_are_jumpers no)
		(fp_line
			(start -0.7874 0.4064)
			(end -0.7874 -0.4064)
			(stroke
				(width 0.1524)
				(type default)
			)
			(layer "F.SilkS")
		)
		(fp_line
			(start 0.7874 0.4064)
			(end -0.7874 0.4064)
			(stroke
				(width 0.1524)
				(type default)
			)
			(layer "F.SilkS")
		)
		(fp_line
			(start -0.7874 -0.4064)
			(end 0.7874 -0.4064)
			(stroke
				(width 0.1524)
				(type default)
			)
			(layer "F.SilkS")
		)
		(fp_line
			(start 0.7874 -0.4064)
			(end 0.7874 0.4064)
			(stroke
				(width 0.1524)
				(type default)
			)
			(layer "F.SilkS")
		)
		(fp_line
			(start -0.67945 0.3048)
			(end -0.67945 -0.305054)
			(stroke
				(width 0.1)
				(type default)
			)
			(layer "F.Fab")
		)
		(fp_line
			(start -0.12065 0.3048)
			(end -0.67945 0.3048)
			(stroke
				(width 0.1)
				(type default)
			)
			(layer "F.Fab")
		)
		(fp_line
			(start 0.120396 0.3048)
			(end 0.120396 0.2794)
			(stroke
				(width 0.1)
				(type default)
			)
			(layer "F.Fab")
		)
		(fp_line
			(start 0.67945 0.3048)
			(end 0.120396 0.3048)
			(stroke
				(width 0.1)
				(type default)
			)
			(layer "F.Fab")
		)
		(fp_line
			(start -0.12065 0.2794)
			(end -0.12065 0.3048)
			(stroke
				(width 0.1)
				(type default)
			)
			(layer "F.Fab")
		)
		(fp_line
			(start 0.120396 0.2794)
			(end -0.12065 0.2794)
			(stroke
				(width 0.1)
				(type default)
			)
			(layer "F.Fab")
		)
		(fp_line
			(start -0.12065 -0.2794)
			(end 0.12065 -0.2794)
			(stroke
				(width 0.1)
				(type default)
			)
			(layer "F.Fab")
		)
		(fp_line
			(start 0.12065 -0.2794)
			(end 0.12065 -0.3048)
			(stroke
				(width 0.1)
				(type default)
			)
			(layer "F.Fab")
		)
		(fp_line
			(start 0.12065 -0.3048)
			(end 0.67945 -0.3048)
			(stroke
				(width 0.1)
				(type default)
			)
			(layer "F.Fab")
		)
		(fp_line
			(start 0.67945 -0.3048)
			(end 0.67945 0.3048)
			(stroke
				(width 0.1)
				(type default)
			)
			(layer "F.Fab")
		)
		(fp_line
			(start -0.67945 -0.305054)
			(end -0.12065 -0.305054)
			(stroke
				(width 0.1)
				(type default)
			)
			(layer "F.Fab")
		)
		(fp_line
			(start -0.12065 -0.305054)
			(end -0.12065 -0.2794)
			(stroke
				(width 0.1)
				(type default)
			)
			(layer "F.Fab")
		)
		(pad "1" smd circle
			(at -0.40005 0 270)
			(size 0 0)
			(layers "F.Cu" "F.Mask" "F.Paste")
			(net "P3V3_SSD15_CO_MODE")
		)
		(pad "2" smd circle
			(at 0.40005 0 270)
			(size 0 0)
			(layers "F.Cu" "F.Mask" "F.Paste")
			(net "GND")
		)
	)
	(footprint ""
		(layer "F.Cu")
		(at 268.786102 -350.098614 90)
		(property "Reference" "C614"
			(at 0 0 90)
			(layer "F.SilkS")
			(hide yes)
			(effects
				(font
					(size 1.27 1.27)
				)
			)
		)
		(property "Value" ""
			(at 0 0 90)
			(layer "F.Fab")
			(effects
				(font
					(size 1.27 1.27)
				)
			)
		)
		(duplicate_pad_numbers_are_jumpers no)
		(fp_line
			(start 0.299974 -0.150114)
			(end 0.299974 0.150114)
			(stroke
				(width 0.1)
				(type default)
			)
			(layer "F.Fab")
		)
		(fp_line
			(start -0.299974 -0.150114)
			(end 0.299974 -0.150114)
			(stroke
				(width 0.1)
				(type default)
			)
			(layer "F.Fab")
		)
		(fp_line
			(start 0.299974 0.150114)
			(end -0.299974 0.150114)
			(stroke
				(width 0.1)
				(type default)
			)
			(layer "F.Fab")
		)
		(fp_line
			(start -0.299974 0.150114)
			(end -0.299974 -0.150114)
			(stroke
				(width 0.1)
				(type default)
			)
			(layer "F.Fab")
		)
		(pad "1" smd rect
			(at -0.2667 0 90)
			(size 0.3048 0.381)
			(layers "F.Cu" "F.Mask" "F.Paste")
			(net "P5E_PEX2_STN7_TX_DN<112>")
		)
		(pad "2" smd rect
			(at 0.2667 0 90)
			(size 0.3048 0.381)
			(layers "F.Cu" "F.Mask" "F.Paste")
			(net "P5E_PEX2_STN7_TX_C_DN<112>")
		)
	)
	(footprint ""
		(layer "F.Cu")
		(at 407.295096 -99.750372 180)
		(property "Reference" "R385"
			(at 0 0 180)
			(layer "F.SilkS")
			(hide yes)
			(effects
				(font
					(size 1.27 1.27)
				)
			)
		)
		(property "Value" ""
			(at 0 0 180)
			(layer "F.Fab")
			(effects
				(font
					(size 1.27 1.27)
				)
			)
		)
		(duplicate_pad_numbers_are_jumpers no)
		(fp_line
			(start 0.7874 0.4064)
			(end -0.7874 0.4064)
			(stroke
				(width 0.1524)
				(type default)
			)
			(layer "F.SilkS")
		)
		(fp_line
			(start 0.7874 -0.4064)
			(end 0.7874 0.4064)
			(stroke
				(width 0.1524)
				(type default)
			)
			(layer "F.SilkS")
		)
		(fp_line
			(start -0.7874 0.4064)
			(end -0.7874 -0.4064)
			(stroke
				(width 0.1524)
				(type default)
			)
			(layer "F.SilkS")
		)
		(fp_line
			(start -0.7874 -0.4064)
			(end 0.7874 -0.4064)
			(stroke
				(width 0.1524)
				(type default)
			)
			(layer "F.SilkS")
		)
		(fp_line
			(start 0.67945 0.3048)
			(end 0.120396 0.3048)
			(stroke
				(width 0.1)
				(type default)
			)
			(layer "F.Fab")
		)
		(fp_line
			(start 0.67945 -0.3048)
			(end 0.67945 0.3048)
			(stroke
				(width 0.1)
				(type default)
			)
			(layer "F.Fab")
		)
		(fp_line
			(start 0.12065 -0.2794)
			(end 0.12065 -0.3048)
			(stroke
				(width 0.1)
				(type default)
			)
			(layer "F.Fab")
		)
		(fp_line
			(start 0.12065 -0.3048)
			(end 0.67945 -0.3048)
			(stroke
				(width 0.1)
				(type default)
			)
			(layer "F.Fab")
		)
		(fp_line
			(start 0.120396 0.3048)
			(end 0.120396 0.2794)
			(stroke
				(width 0.1)
				(type default)
			)
			(layer "F.Fab")
		)
		(fp_line
			(start 0.120396 0.2794)
			(end -0.12065 0.2794)
			(stroke
				(width 0.1)
				(type default)
			)
			(layer "F.Fab")
		)
		(fp_line
			(start -0.12065 0.3048)
			(end -0.67945 0.3048)
			(stroke
				(width 0.1)
				(type default)
			)
			(layer "F.Fab")
		)
		(fp_line
			(start -0.12065 0.2794)
			(end -0.12065 0.3048)
			(stroke
				(width 0.1)
				(type default)
			)
			(layer "F.Fab")
		)
		(fp_line
			(start -0.12065 -0.2794)
			(end 0.12065 -0.2794)
			(stroke
				(width 0.1)
				(type default)
			)
			(layer "F.Fab")
		)
		(fp_line
			(start -0.12065 -0.305054)
			(end -0.12065 -0.2794)
			(stroke
				(width 0.1)
				(type default)
			)
			(layer "F.Fab")
		)
		(fp_line
			(start -0.67945 0.3048)
			(end -0.67945 -0.305054)
			(stroke
				(width 0.1)
				(type default)
			)
			(layer "F.Fab")
		)
		(fp_line
			(start -0.67945 -0.305054)
			(end -0.12065 -0.305054)
			(stroke
				(width 0.1)
				(type default)
			)
			(layer "F.Fab")
		)
		(pad "1" smd circle
			(at -0.40005 0 180)
			(size 0 0)
			(layers "F.Cu" "F.Mask" "F.Paste")
			(net "NIC7_SLOT_ID1")
		)
		(pad "2" smd circle
			(at 0.40005 0 180)
			(size 0 0)
			(layers "F.Cu" "F.Mask" "F.Paste")
			(net "GND")
		)
	)
)
